# T6G (Grand Teton) — schematic netlist excerpt (pin names and nets, part order shuffled) for the footprints in the layout excerpt that follows; sources: Cadence DE-HDL packaged netlist, KiCad conversion of 04192023_DAF0TMB3IC0_F0TG_MB_C_brd_V02_OCP.brd

R6799  Q_RES  0 5% CHIP  pkg 0402LF  page 81 : A = RST_RT_CPU1_P3_RESET_R_N ; B = RST_RT_CPU1_P3_RESET_R2_N
R299  Q_RES  1K 1% CHIP  pkg 0402LF  page 94 : A = PWRGD_CHI_CPU0_DIMM ; B = PWRGD_CHGL_CPU0

(kicad_pcb
	(version 20260206)
	(generator "pcbnew")
	(generator_version "10.0")
	(general
		(thickness 1.6)
		(legacy_teardrops no)
	)
	(paper "A4")
	(title_block
		(title "04192023_DAF0TMB3IC0_F0TG_MB_C_brd_V02_OCP.brd")
		(comment 1 "Grand Teton / footprints 5529-5530 of 8354")
	)
	(layers
		(0 "F.Cu" signal "TOP")
		(4 "In1.Cu" signal "GND")
		(6 "In2.Cu" signal "IN1")
		(8 "In3.Cu" signal "GND1")
		(10 "In4.Cu" signal "IN2")
		(12 "In5.Cu" signal "GND2")
		(14 "In6.Cu" signal "IN3")
		(16 "In7.Cu" signal "GND3")
		(18 "In8.Cu" signal "VCC")
		(20 "In9.Cu" signal "VCC1")
		(22 "In10.Cu" signal "GND4")
		(24 "In11.Cu" signal "IN4")
		(26 "In12.Cu" signal "GND5")
		(28 "In13.Cu" signal "IN5")
		(30 "In14.Cu" signal "GND6")
		(32 "In15.Cu" signal "IN6")
		(34 "In16.Cu" signal "GND7")
		(2 "B.Cu" signal "BOTTOM")
		(9 "F.Adhes" user "F.Adhesive")
		(11 "B.Adhes" user "B.Adhesive")
		(13 "F.Paste" user "Package Geometry/Pastemask Top")
		(15 "B.Paste" user "Package Geometry/Pastemask Bottom")
		(5 "F.SilkS" user "Ref Des/Silkscreen Top")
		(7 "B.SilkS" user "Ref Des/Silkscreen Bottom")
		(1 "F.Mask" user "Board Geometry/Soldermask Top")
		(3 "B.Mask" user "Board Geometry/Soldermask Bottom")
		(17 "Dwgs.User" user "User.Drawings")
		(19 "Cmts.User" user "User.Comments")
		(21 "Eco1.User" user "User.Eco1")
		(23 "Eco2.User" user "User.Eco2")
		(25 "Edge.Cuts" user "Board Geometry/Outline")
		(27 "Margin" user)
		(31 "F.CrtYd" user "Package Geometry/Place Bound Top")
		(29 "B.CrtYd" user "Package Geometry/Place Bound Bottom")
		(35 "F.Fab" user "Ref Des/Assembly Top")
		(33 "B.Fab" user "Ref Des/Assembly Bottom")
	)
	(footprint ""
		(layer "B.Cu")
		(at 427.558454 -191.32931 180)
		(property "Reference" "R299"
			(at 0 0 0)
			(layer "B.SilkS")
			(hide yes)
			(effects
				(font
					(size 1.27 1.27)
				)
				(justify mirror)
			)
		)
		(property "Value" ""
			(at 0 0 0)
			(layer "B.Fab")
			(effects
				(font
					(size 1.27 1.27)
				)
				(justify mirror)
			)
		)
		(duplicate_pad_numbers_are_jumpers no)
		(fp_line
			(start 0.7874 0.4064)
			(end 0.7874 -0.4064)
			(stroke
				(width 0.1524)
				(type default)
			)
			(layer "B.SilkS")
		)
		(fp_line
			(start 0.7874 -0.4064)
			(end -0.7874 -0.4064)
			(stroke
				(width 0.1524)
				(type default)
			)
			(layer "B.SilkS")
		)
		(fp_line
			(start -0.7874 0.4064)
			(end 0.7874 0.4064)
			(stroke
				(width 0.1524)
				(type default)
			)
			(layer "B.SilkS")
		)
		(fp_line
			(start -0.7874 -0.4064)
			(end -0.7874 0.4064)
			(stroke
				(width 0.1524)
				(type default)
			)
			(layer "B.SilkS")
		)
		(fp_line
			(start 0.67945 0.3048)
			(end 0.67945 -0.305054)
			(stroke
				(width 0.1)
				(type default)
			)
			(layer "B.Fab")
		)
		(fp_line
			(start 0.67945 -0.305054)
			(end 0.12065 -0.305054)
			(stroke
				(width 0.1)
				(type default)
			)
			(layer "B.Fab")
		)
		(fp_line
			(start 0.12065 0.3048)
			(end 0.67945 0.3048)
			(stroke
				(width 0.1)
				(type default)
			)
			(layer "B.Fab")
		)
		(fp_line
			(start 0.12065 0.2794)
			(end 0.12065 0.3048)
			(stroke
				(width 0.1)
				(type default)
			)
			(layer "B.Fab")
		)
		(fp_line
			(start 0.12065 -0.2794)
			(end -0.12065 -0.2794)
			(stroke
				(width 0.1)
				(type default)
			)
			(layer "B.Fab")
		)
		(fp_line
			(start 0.12065 -0.305054)
			(end 0.12065 -0.2794)
			(stroke
				(width 0.1)
				(type default)
			)
			(layer "B.Fab")
		)
		(fp_line
			(start -0.120396 0.3048)
			(end -0.120396 0.2794)
			(stroke
				(width 0.1)
				(type default)
			)
			(layer "B.Fab")
		)
		(fp_line
			(start -0.120396 0.2794)
			(end 0.12065 0.2794)
			(stroke
				(width 0.1)
				(type default)
			)
			(layer "B.Fab")
		)
		(fp_line
			(start -0.12065 -0.2794)
			(end -0.12065 -0.3048)
			(stroke
				(width 0.1)
				(type default)
			)
			(layer "B.Fab")
		)
		(fp_line
			(start -0.12065 -0.3048)
			(end -0.67945 -0.3048)
			(stroke
				(width 0.1)
				(type default)
			)
			(layer "B.Fab")
		)
		(fp_line
			(start -0.67945 0.3048)
			(end -0.120396 0.3048)
			(stroke
				(width 0.1)
				(type default)
			)
			(layer "B.Fab")
		)
		(fp_line
			(start -0.67945 -0.3048)
			(end -0.67945 0.3048)
			(stroke
				(width 0.1)
				(type default)
			)
			(layer "B.Fab")
		)
		(pad "1" smd circle
			(at 0.40005 0)
			(size 0 0)
			(layers "B.Cu" "B.Mask" "B.Paste")
			(net "PWRGD_CHI_CPU0_DIMM")
		)
		(pad "2" smd circle
			(at -0.40005 0)
			(size 0 0)
			(layers "B.Cu" "B.Mask" "B.Paste")
			(net "PWRGD_CHGL_CPU0")
		)
	)
	(footprint ""
		(layer "B.Cu")
		(at 186.22264 -133.208014 90)
		(property "Reference" "R6799"
			(at 0 0 90)
			(layer "B.SilkS")
			(hide yes)
			(effects
				(font
					(size 1.27 1.27)
				)
				(justify mirror)
			)
		)
		(property "Value" ""
			(at 0 0 90)
			(layer "B.Fab")
			(effects
				(font
					(size 1.27 1.27)
				)
				(justify mirror)
			)
		)
		(duplicate_pad_numbers_are_jumpers no)
		(fp_line
			(start 0.7874 -0.4064)
			(end -0.7874 -0.4064)
			(stroke
				(width 0.1524)
				(type default)
			)
			(layer "B.SilkS")
		)
		(fp_line
			(start -0.7874 -0.4064)
			(end -0.7874 0.4064)
			(stroke
				(width 0.1524)
				(type default)
			)
			(layer "B.SilkS")
		)
		(fp_line
			(start 0.7874 0.4064)
			(end 0.7874 -0.4064)
			(stroke
				(width 0.1524)
				(type default)
			)
			(layer "B.SilkS")
		)
		(fp_line
			(start -0.7874 0.4064)
			(end 0.7874 0.4064)
			(stroke
				(width 0.1524)
				(type default)
			)
			(layer "B.SilkS")
		)
		(fp_line
			(start 0.67945 -0.305054)
			(end 0.12065 -0.305054)
			(stroke
				(width 0.1)
				(type default)
			)
			(layer "B.Fab")
		)
		(fp_line
			(start 0.12065 -0.305054)
			(end 0.12065 -0.2794)
			(stroke
				(width 0.1)
				(type default)
			)
			(layer "B.Fab")
		)
		(fp_line
			(start -0.12065 -0.3048)
			(end -0.67945 -0.3048)
			(stroke
				(width 0.1)
				(type default)
			)
			(layer "B.Fab")
		)
		(fp_line
			(start -0.67945 -0.3048)
			(end -0.67945 0.3048)
			(stroke
				(width 0.1)
				(type default)
			)
			(layer "B.Fab")
		)
		(fp_line
			(start 0.12065 -0.2794)
			(end -0.12065 -0.2794)
			(stroke
				(width 0.1)
				(type default)
			)
			(layer "B.Fab")
		)
		(fp_line
			(start -0.12065 -0.2794)
			(end -0.12065 -0.3048)
			(stroke
				(width 0.1)
				(type default)
			)
			(layer "B.Fab")
		)
		(fp_line
			(start 0.12065 0.2794)
			(end 0.12065 0.3048)
			(stroke
				(width 0.1)
				(type default)
			)
			(layer "B.Fab")
		)
		(fp_line
			(start -0.120396 0.2794)
			(end 0.12065 0.2794)
			(stroke
				(width 0.1)
				(type default)
			)
			(layer "B.Fab")
		)
		(fp_line
			(start 0.67945 0.3048)
			(end 0.67945 -0.305054)
			(stroke
				(width 0.1)
				(type default)
			)
			(layer "B.Fab")
		)
		(fp_line
			(start 0.12065 0.3048)
			(end 0.67945 0.3048)
			(stroke
				(width 0.1)
				(type default)
			)
			(layer "B.Fab")
		)
		(fp_line
			(start -0.120396 0.3048)
			(end -0.120396 0.2794)
			(stroke
				(width 0.1)
				(type default)
			)
			(layer "B.Fab")
		)
		(fp_line
			(start -0.67945 0.3048)
			(end -0.120396 0.3048)
			(stroke
				(width 0.1)
				(type default)
			)
			(layer "B.Fab")
		)
		(pad "1" smd circle
			(at 0.40005 0 270)
			(size 0 0)
			(layers "B.Cu" "B.Mask" "B.Paste")
			(net "RST_RT_CPU1_P3_RESET_R_N")
		)
		(pad "2" smd circle
			(at -0.40005 0 270)
			(size 0 0)
			(layers "B.Cu" "B.Mask" "B.Paste")
			(net "RST_RT_CPU1_P3_RESET_R2_N")
		)
	)
)
